(kicad_pcb
	(version 20260206)
	(generator "pcbnew")
	(generator_version "10.0")
	(general
		(thickness 1.6)
		(legacy_teardrops no)
	)
	(paper "A4")
	(title_block
		(title "baseboard — 13948-1b.1110WZS1818.brd")
		(comment 1 "Honey Badger (Wiwynn) / footprints 1615-1619 of 2523")
	)
	(layers
		(0 "F.Cu" signal "TOP")
		(4 "In1.Cu" signal "L2GND")
		(6 "In2.Cu" signal "L3")
		(8 "In3.Cu" signal "L4VCC")
		(10 "In4.Cu" signal "L5VCC")
		(12 "In5.Cu" signal "L6")
		(14 "In6.Cu" signal "L7GND")
		(2 "B.Cu" signal "BOTTOM")
		(9 "F.Adhes" user "F.Adhesive")
		(11 "B.Adhes" user "B.Adhesive")
		(13 "F.Paste" user "Package Geometry/Pastemask Top")
		(15 "B.Paste" user "Package Geometry/Pastemask Bottom")
		(5 "F.SilkS" user "Ref Des/Silkscreen Top")
		(7 "B.SilkS" user "Ref Des/Silkscreen Bottom")
		(1 "F.Mask" user "Board Geometry/Soldermask Top")
		(3 "B.Mask" user "Board Geometry/Soldermask Bottom")
		(17 "Dwgs.User" user "User.Drawings")
		(19 "Cmts.User" user "User.Comments")
		(21 "Eco1.User" user "User.Eco1")
		(23 "Eco2.User" user "User.Eco2")
		(25 "Edge.Cuts" user "Board Geometry/Outline")
		(27 "Margin" user)
		(31 "F.CrtYd" user "Package Geometry/Place Bound Top")
		(29 "B.CrtYd" user "Package Geometry/Place Bound Bottom")
		(35 "F.Fab" user "Ref Des/Assembly Top")
		(33 "B.Fab" user "Ref Des/Assembly Bottom")
	)
	(footprint ""
		(layer "F.Cu")
		(at 282.194 -161.544 180)
		(property "Reference" "R237"
			(at 0 0 180)
			(layer "F.SilkS")
			(hide yes)
			(effects
				(font
					(size 1.27 1.27)
				)
			)
		)
		(property "Value" "100KR2F-L1-GP"
			(at 0.064008 -3.993896 180)
			(unlocked yes)
			(layer "F.Fab")
			(hide yes)
			(effects
				(font
					(size 1.016 1.016)
					(thickness 0.1524)
				)
			)
		)
		(property "Device Type" "R402H16"
			(at 0.064008 -5.517896 180)
			(unlocked yes)
			(layer "F.Fab")
			(hide yes)
			(effects
				(font
					(size 1.016 1.016)
					(thickness 0.1524)
				)
			)
		)
		(duplicate_pad_numbers_are_jumpers no)
		(fp_line
			(start 0.508 -0.9398)
			(end -0.508 -0.9398)
			(stroke
				(width 0.1524)
				(type default)
			)
			(layer "F.SilkS")
		)
		(fp_line
			(start -0.508 -0.9398)
			(end -0.508 0.9398)
			(stroke
				(width 0.1524)
				(type default)
			)
			(layer "F.SilkS")
		)
		(fp_rect
			(start -0.508 0.9398)
			(end 0.508 -0.9398)
			(stroke
				(width 0)
				(type default)
			)
			(fill no)
			(layer "F.CrtYd")
		)
		(fp_rect
			(start -0.508 0.9398)
			(end 0.508 -0.9398)
			(stroke
				(width 0)
				(type default)
			)
			(fill no)
			(layer "F.Fab")
		)
		(pad "1" smd custom
			(at 0 -0.4445 180)
			(size 0.1397 0.1397)
			(layers "F.Cu" "F.Mask" "F.Paste")
			(net "GND")
			(options
				(clearance outline)
				(anchor circle)
			)
			(primitives
				(gr_poly
					(pts
						(arc
							(start -0.1778 -0.2794)
							(mid -0.249642 -0.249642)
							(end -0.2794 -0.1778)
						)
						(arc
							(start -0.2794 0.1778)
							(mid -0.249642 0.249642)
							(end -0.1778 0.2794)
						)
						(arc
							(start 0.1778 0.2794)
							(mid 0.249642 0.249642)
							(end 0.2794 0.1778)
						)
						(arc
							(start 0.2794 -0.1778)
							(mid 0.249642 -0.249642)
							(end 0.1778 -0.2794)
						)
					)
					(width 0)
					(fill yes)
				)
			)
		)
		(pad "2" smd custom
			(at 0 0.4445 180)
			(size 0.1397 0.1397)
			(layers "F.Cu" "F.Mask" "F.Paste")
			(net "TP_BMC0_LPC_LAD3")
			(options
				(clearance outline)
				(anchor circle)
			)
			(primitives
				(gr_poly
					(pts
						(arc
							(start -0.1778 -0.2794)
							(mid -0.249642 -0.249642)
							(end -0.2794 -0.1778)
						)
						(arc
							(start -0.2794 0.1778)
							(mid -0.249642 0.249642)
							(end -0.1778 0.2794)
						)
						(arc
							(start 0.1778 0.2794)
							(mid 0.249642 0.249642)
							(end 0.2794 0.1778)
						)
						(arc
							(start 0.2794 -0.1778)
							(mid 0.249642 -0.249642)
							(end 0.1778 -0.2794)
						)
					)
					(width 0)
					(fill yes)
				)
			)
		)
	)
	(footprint ""
		(layer "F.Cu")
		(at 69.763386 -109.392212 -90)
		(property "Reference" "PQ4"
			(at 0 0 270)
			(layer "F.SilkS")
			(hide yes)
			(effects
				(font
					(size 1.27 1.27)
				)
			)
		)
		(property "Value" "2N7002A-7-GP"
			(at 0.127 -8.9662 270)
			(unlocked yes)
			(layer "F.Fab")
			(hide yes)
			(effects
				(font
					(size 1.016 1.016)
					(thickness 0.1524)
				)
			)
		)
		(property "Device Type" "SOT23DGS2D4H48"
			(at 0.127 -10.4902 270)
			(unlocked yes)
			(layer "F.Fab")
			(hide yes)
			(effects
				(font
					(size 1.016 1.016)
					(thickness 0.1524)
				)
			)
		)
		(duplicate_pad_numbers_are_jumpers no)
		(fp_line
			(start -1.651 1.778)
			(end 1.651 1.778)
			(stroke
				(width 0.1524)
				(type default)
			)
			(layer "F.SilkS")
		)
		(fp_line
			(start 1.651 1.778)
			(end 1.651 -1.778)
			(stroke
				(width 0.1524)
				(type default)
			)
			(layer "F.SilkS")
		)
		(fp_line
			(start -1.651 -1.778)
			(end -1.651 1.778)
			(stroke
				(width 0.1524)
				(type default)
			)
			(layer "F.SilkS")
		)
		(fp_line
			(start 1.651 -1.778)
			(end -1.651 -1.778)
			(stroke
				(width 0.1524)
				(type default)
			)
			(layer "F.SilkS")
		)
		(fp_poly
			(pts
				(xy -1.778 1.8796) (xy -1.778 -1.8796) (xy 1.778 -1.8796) (xy 1.778 1.8796)
			)
			(stroke
				(width 0)
				(type default)
			)
			(fill no)
			(layer "F.CrtYd")
		)
		(fp_poly
			(pts
				(xy -1.778 1.8796) (xy -1.778 -1.8796) (xy 1.778 -1.8796) (xy 1.778 1.8796)
			)
			(stroke
				(width 0)
				(type default)
			)
			(fill no)
			(layer "F.Fab")
		)
		(pad "D" smd custom
			(at 0 -0.9525 270)
			(size 0.1905 0.1905)
			(layers "F.Cu" "F.Mask" "F.Paste")
			(net "P1V8_EN_LV")
			(options
				(clearance outline)
				(anchor circle)
			)
			(primitives
				(gr_poly
					(pts
						(arc
							(start -0.1778 0.5715)
							(mid -0.321484 0.511984)
							(end -0.381 0.3683)
						)
						(arc
							(start -0.381 -0.3683)
							(mid -0.321484 -0.511984)
							(end -0.1778 -0.5715)
						)
						(arc
							(start 0.1778 -0.5715)
							(mid 0.321484 -0.511984)
							(end 0.381 -0.3683)
						)
						(arc
							(start 0.381 0.3683)
							(mid 0.321484 0.511984)
							(end 0.1778 0.5715)
						)
					)
					(width 0)
					(fill yes)
				)
			)
		)
		(pad "G" smd custom
			(at -0.98425 0.9525 270)
			(size 0.1905 0.1905)
			(layers "F.Cu" "F.Mask" "F.Paste")
			(net "P1V8_EN_G")
			(options
				(clearance outline)
				(anchor circle)
			)
			(primitives
				(gr_poly
					(pts
						(arc
							(start -0.1778 0.5715)
							(mid -0.321484 0.511984)
							(end -0.381 0.3683)
						)
						(arc
							(start -0.381 -0.3683)
							(mid -0.321484 -0.511984)
							(end -0.1778 -0.5715)
						)
						(arc
							(start 0.1778 -0.5715)
							(mid 0.321484 -0.511984)
							(end 0.381 -0.3683)
						)
						(arc
							(start 0.381 0.3683)
							(mid 0.321484 0.511984)
							(end 0.1778 0.5715)
						)
					)
					(width 0)
					(fill yes)
				)
			)
		)
		(pad "S" smd custom
			(at 0.98425 0.9525 270)
			(size 0.1905 0.1905)
			(layers "F.Cu" "F.Mask" "F.Paste")
			(net "P1V8_EN_S")
			(options
				(clearance outline)
				(anchor circle)
			)
			(primitives
				(gr_poly
					(pts
						(arc
							(start -0.1778 0.5715)
							(mid -0.321484 0.511984)
							(end -0.381 0.3683)
						)
						(arc
							(start -0.381 -0.3683)
							(mid -0.321484 -0.511984)
							(end -0.1778 -0.5715)
						)
						(arc
							(start 0.1778 -0.5715)
							(mid 0.321484 -0.511984)
							(end 0.381 -0.3683)
						)
						(arc
							(start 0.381 0.3683)
							(mid 0.321484 0.511984)
							(end 0.1778 0.5715)
						)
					)
					(width 0)
					(fill yes)
				)
			)
		)
	)
	(footprint ""
		(layer "F.Cu")
		(at 174.743872 -193.797936)
		(property "Reference" "C245"
			(at 0 0 0)
			(layer "F.SilkS")
			(hide yes)
			(effects
				(font
					(size 1.27 1.27)
				)
			)
		)
		(property "Value" "SC220P50V3JN-GP"
			(at 0 -2.8194 0)
			(unlocked yes)
			(layer "F.Fab")
			(hide yes)
			(effects
				(font
					(size 1.016 1.016)
					(thickness 0.1524)
				)
			)
		)
		(property "Device Type" "C603H36"
			(at 0 -4.3434 0)
			(unlocked yes)
			(layer "F.Fab")
			(hide yes)
			(effects
				(font
					(size 1.016 1.016)
					(thickness 0.1524)
				)
			)
		)
		(duplicate_pad_numbers_are_jumpers no)
		(fp_line
			(start 0.508 0)
			(end -0.508 0)
			(stroke
				(width 0.2032)
				(type default)
			)
			(layer "F.SilkS")
		)
		(fp_rect
			(start -0.5842 1.3335)
			(end 0.5842 -1.3335)
			(stroke
				(width 0)
				(type default)
			)
			(fill no)
			(layer "F.CrtYd")
		)
		(fp_rect
			(start -0.5842 1.3335)
			(end 0.5842 -1.3335)
			(stroke
				(width 0)
				(type default)
			)
			(fill no)
			(layer "F.Fab")
		)
		(pad "1" smd custom
			(at 0 -0.762)
			(size 0.2159 0.2159)
			(layers "F.Cu" "F.Mask" "F.Paste")
			(net "SAS_I2C_C_BUF_SCL")
			(options
				(clearance outline)
				(anchor circle)
			)
			(primitives
				(gr_poly
					(pts
						(arc
							(start -0.3302 -0.4318)
							(mid -0.402042 -0.402042)
							(end -0.4318 -0.3302)
						)
						(arc
							(start -0.4318 0.3302)
							(mid -0.402042 0.402042)
							(end -0.3302 0.4318)
						)
						(arc
							(start 0.3302 0.4318)
							(mid 0.402042 0.402042)
							(end 0.4318 0.3302)
						)
						(arc
							(start 0.4318 -0.3302)
							(mid 0.402042 -0.402042)
							(end 0.3302 -0.4318)
						)
					)
					(width 0)
					(fill yes)
				)
			)
		)
		(pad "2" smd custom
			(at 0 0.762)
			(size 0.2159 0.2159)
			(layers "F.Cu" "F.Mask" "F.Paste")
			(net "GND")
			(options
				(clearance outline)
				(anchor circle)
			)
			(primitives
				(gr_poly
					(pts
						(arc
							(start -0.3302 -0.4318)
							(mid -0.402042 -0.402042)
							(end -0.4318 -0.3302)
						)
						(arc
							(start -0.4318 0.3302)
							(mid -0.402042 0.402042)
							(end -0.3302 0.4318)
						)
						(arc
							(start 0.3302 0.4318)
							(mid 0.402042 0.402042)
							(end 0.4318 0.3302)
						)
						(arc
							(start 0.4318 -0.3302)
							(mid 0.402042 -0.402042)
							(end 0.3302 -0.4318)
						)
					)
					(width 0)
					(fill yes)
				)
			)
		)
	)
	(footprint ""
		(layer "F.Cu")
		(at 202.556872 -191.461136)
		(property "Reference" "U41"
			(at 0 0 0)
			(layer "F.SilkS")
			(hide yes)
			(effects
				(font
					(size 1.27 1.27)
				)
			)
		)
		(property "Value" "LM393ADR-1-GP"
			(at -3.707384 -1.5367 0)
			(unlocked yes)
			(layer "F.Fab")
			(hide yes)
			(effects
				(font
					(size 1.016 1.016)
					(thickness 0.1524)
				)
			)
		)
		(property "Device Type" "SOIC8H69"
			(at -3.707384 -3.0607 0)
			(unlocked yes)
			(layer "F.Fab")
			(hide yes)
			(effects
				(font
					(size 1.016 1.016)
					(thickness 0.1524)
				)
			)
		)
		(duplicate_pad_numbers_are_jumpers no)
		(fp_line
			(start -2.7432 -1.4224)
			(end -2.7432 1.4224)
			(stroke
				(width 0.1524)
				(type default)
			)
			(layer "F.SilkS")
		)
		(fp_line
			(start -2.7432 1.4224)
			(end -2.6416 1.4224)
			(stroke
				(width 0.1524)
				(type default)
			)
			(layer "F.SilkS")
		)
		(fp_line
			(start -2.7432 1.4224)
			(end 2.1336 1.4224)
			(stroke
				(width 0.1524)
				(type default)
			)
			(layer "F.SilkS")
		)
		(fp_line
			(start -2.7178 -0.508)
			(end -2.1844 -0.0508)
			(stroke
				(width 0.1524)
				(type default)
			)
			(layer "F.SilkS")
		)
		(fp_line
			(start -2.6289 3.4417)
			(end -2.6289 1.4732)
			(stroke
				(width 0.381)
				(type default)
			)
			(layer "F.SilkS")
		)
		(fp_line
			(start -2.1844 -0.0508)
			(end -2.7178 0.508)
			(stroke
				(width 0.1524)
				(type default)
			)
			(layer "F.SilkS")
		)
		(fp_line
			(start 2.1336 -1.4224)
			(end -2.7432 -1.4224)
			(stroke
				(width 0.1524)
				(type default)
			)
			(layer "F.SilkS")
		)
		(fp_line
			(start 2.1336 1.4224)
			(end 2.1336 -1.4224)
			(stroke
				(width 0.1524)
				(type default)
			)
			(layer "F.SilkS")
		)
		(fp_poly
			(pts
				(xy -2.2098 -1.4224) (xy -2.2098 1.4224) (xy 2.2098 1.4224) (xy 2.2098 -1.4224)
			)
			(stroke
				(width 0)
				(type default)
			)
			(fill yes)
			(layer "F.SilkS")
		)
		(fp_rect
			(start -2.450084 2.999994)
			(end 2.450084 -2.999994)
			(stroke
				(width 0)
				(type default)
			)
			(fill no)
			(layer "F.CrtYd")
		)
		(fp_poly
			(pts
				(xy -2.8194 3.6322) (xy -2.8194 -3.6322) (xy 2.8194 -3.6322) (xy 2.8194 1.18364) (xy 2.450084 1.18364)
				(xy 2.450084 -2.999994) (xy -2.450084 -2.999994) (xy -2.450084 2.999994) (xy 2.450084 2.999994)
				(xy 2.450084 1.18618) (xy 2.8194 1.18618) (xy 2.8194 3.6322)
			)
			(stroke
				(width 0)
				(type default)
			)
			(fill no)
			(layer "F.CrtYd")
		)
		(fp_rect
			(start -2.8194 3.6322)
			(end 2.8194 -3.6322)
			(stroke
				(width 0)
				(type default)
			)
			(fill no)
			(layer "F.Fab")
		)
		(pad "1" smd rect
			(at -1.905 2.54)
			(size 0.635 1.651)
			(layers "F.Cu" "F.Mask" "F.Paste")
			(net "HB_A_OUT")
		)
		(pad "2" smd rect
			(at -0.635 2.54)
			(size 0.635 1.651)
			(layers "F.Cu" "F.Mask" "F.Paste")
			(net "HB_A_IN")
		)
		(pad "3" smd rect
			(at 0.635 2.54)
			(size 0.635 1.651)
			(layers "F.Cu" "F.Mask" "F.Paste")
			(net "DIVIDER 1_IN")
		)
		(pad "4" smd rect
			(at 1.905 2.54)
			(size 0.635 1.651)
			(layers "F.Cu" "F.Mask" "F.Paste")
			(net "GND")
		)
		(pad "5" smd rect
			(at 1.905 -2.54)
			(size 0.635 1.651)
			(layers "F.Cu" "F.Mask" "F.Paste")
			(net "HB_A_IN")
		)
		(pad "6" smd rect
			(at 0.635 -2.54)
			(size 0.635 1.651)
			(layers "F.Cu" "F.Mask" "F.Paste")
			(net "DIVIDER 2_IN")
		)
		(pad "7" smd rect
			(at -0.635 -2.54)
			(size 0.635 1.651)
			(layers "F.Cu" "F.Mask" "F.Paste")
			(net "HB_A_OUT")
		)
		(pad "8" smd rect
			(at -1.905 -2.54)
			(size 0.635 1.651)
			(layers "F.Cu" "F.Mask" "F.Paste")
			(net "P3V3_STBY")
		)
	)
	(footprint ""
		(layer "F.Cu")
		(at 159.893 -154.1526 -90)
		(property "Reference" "SR729"
			(at 0 0 270)
			(layer "F.SilkS")
			(hide yes)
			(effects
				(font
					(size 1.27 1.27)
				)
			)
		)
		(property "Value" "0R2J-2-GP"
			(at 0.064008 -3.993896 270)
			(unlocked yes)
			(layer "F.Fab")
			(hide yes)
			(effects
				(font
					(size 1.016 1.016)
					(thickness 0.1524)
				)
			)
		)
		(property "Device Type" "R402H16"
			(at 0.064008 -5.517896 270)
			(unlocked yes)
			(layer "F.Fab")
			(hide yes)
			(effects
				(font
					(size 1.016 1.016)
					(thickness 0.1524)
				)
			)
		)
		(duplicate_pad_numbers_are_jumpers no)
		(fp_line
			(start -0.508 -0.9398)
			(end -0.508 0.9398)
			(stroke
				(width 0.1524)
				(type default)
			)
			(layer "F.SilkS")
		)
		(fp_line
			(start 0.508 -0.9398)
			(end -0.508 -0.9398)
			(stroke
				(width 0.1524)
				(type default)
			)
			(layer "F.SilkS")
		)
		(fp_rect
			(start -0.508 0.9398)
			(end 0.508 -0.9398)
			(stroke
				(width 0)
				(type default)
			)
			(fill no)
			(layer "F.CrtYd")
		)
		(fp_rect
			(start -0.508 0.9398)
			(end 0.508 -0.9398)
			(stroke
				(width 0)
				(type default)
			)
			(fill no)
			(layer "F.Fab")
		)
		(pad "1" smd custom
			(at 0 -0.4445 270)
			(size 0.1397 0.1397)
			(layers "F.Cu" "F.Mask" "F.Paste")
			(net "EXP_IOC_BMC_R_SDA_14")
			(options
				(clearance outline)
				(anchor circle)
			)
			(primitives
				(gr_poly
					(pts
						(arc
							(start -0.1778 -0.2794)
							(mid -0.249642 -0.249642)
							(end -0.2794 -0.1778)
						)
						(arc
							(start -0.2794 0.1778)
							(mid -0.249642 0.249642)
							(end -0.1778 0.2794)
						)
						(arc
							(start 0.1778 0.2794)
							(mid 0.249642 0.249642)
							(end 0.2794 0.1778)
						)
						(arc
							(start 0.2794 -0.1778)
							(mid 0.249642 -0.249642)
							(end 0.1778 -0.2794)
						)
					)
					(width 0)
					(fill yes)
				)
			)
		)
		(pad "2" smd custom
			(at 0 0.4445 270)
			(size 0.1397 0.1397)
			(layers "F.Cu" "F.Mask" "F.Paste")
			(net "EXP_IOC_BMC_SDA_14")
			(options
				(clearance outline)
				(anchor circle)
			)
			(primitives
				(gr_poly
					(pts
						(arc
							(start -0.1778 -0.2794)
							(mid -0.249642 -0.249642)
							(end -0.2794 -0.1778)
						)
						(arc
							(start -0.2794 0.1778)
							(mid -0.249642 0.249642)
							(end -0.1778 0.2794)
						)
						(arc
							(start 0.1778 0.2794)
							(mid 0.249642 0.249642)
							(end 0.2794 0.1778)
						)
						(arc
							(start 0.2794 -0.1778)
							(mid 0.249642 -0.249642)
							(end 0.1778 -0.2794)
						)
					)
					(width 0)
					(fill yes)
				)
			)
		)
	)
)
